FILE_TYPE = CONNECTIVITY;
{Allegro Design Entry HDL 17.2-2016 S081 (4005846) 1/11/2022}
"PAGE_NUMBER" = 35;
0"NC";
1"VCCIO1\g";
2"P3V3_AUX\g";
3"VCCIO1\g";
4"P3V3_AUX\g";
5"BMC_CPLD_GPIO_13_R2";
6"RST_BMC_HW_R";
7"FM_PWR_R_BTN";
8"PWRGD_SYS_PWROK_PLD";
9"USB_OC0_REAR_R_N";
10"SMB_BMC_ALERT12_N";
11"FM_BMC_READY_PLD_N";
12"FM_BIOS_DEBUG_EN_N";
13"PWR_LED";
14"PWRGD_SYS_PWROK";
15"PWRGD_P5V_AUX";
16"PWRGD_P5V_AUX_R1";
17"PWRGD_P3V3_AUX_R1";
18"PWRGD_P2V5_AUX_R1";
19"RST_ROT_CPU_R_N";
20"FM_SLPS3_GF_R_N";
21"FM_SLPS3_GF_N";
22"FM_BMC_EN_DET_R";
23"FM_PCHHOT_R_N";
24"FM_BMC_ONCTL_R_N";
25"SMB_BMC_ALERT16_R2_N";
26"PWRGD_P5V_AUX_R1";
27"PWR_LED_CPLD";
28"PWRGD_P2V5_AUX";
29"PWRGD_P3V3_AUX";
30"RST_BMC_SELF_HW_R2";
31"RST_BMC_SELF_HW";
32"TP_PLD_L3";
33"SMB_BMC_ALERT10_R1_N";
34"SMB_BMC_ALERT9_R1_N";
35"SMB_BMC_ALERT4_R1_N";
36"SMB_BMC_ALERT3_R1_N";
37"FM_PECI_SEL_N";
38"VOL_SEN_ALERT_R";
39"FM_ESPI_PLD_R_EN";
40"FM_THROTTLE_R_N";
41"FM_PMBUS_ALERT_EN";
42"H_CPU0_PROCHOT_LVC1_R_N";
43"RST_MB_STBY_R_N";
44"FM_ADR_TRIGGER_N";
45"AC_PWR_BTN_R2_N";
46"AC_PWR_BTN_R1_N";
47"FM_PWR_BTN";
48"SMB_BMC_ALERT16_N";
49"H_CPU0_MEMTRIP_LVC1_N";
50"FM_SPD_REMOTE_EN_R";
51"H_CPU1_MEMTRIP_LVC1_N";
52"IRQ_SGPIO_R_N";
53"RST_SGPIO_RESET_R_N";
54"BMC_CPLD_GPIO_7_R2";
55"BMC_CPLD_GPIO_12_R2";
56"BMC_CPLD_GPIO_8_R2";
57"BMC_CPLD_GPIO_8";
58"AC_PWR_BTN_R1_N";
59"RST_ROT_CPU_N";
60"RST_BMC_HW";
61"FM_THROTTLE_N";
62"FM_ESPI_PLD_EN";
63"RST_MB_STBY_N";
64"H_CPU0_PROCHOT_LVC1_N";
65"IRQ_SGPIO_N";
66"RST_SGPIO_RESET_N";
67"BMC_CPLD_GPIO_7";
68"BMC_CPLD_GPIO_13";
69"BMC_CPLD_GPIO_12";
70"SMB_BMC_ALERT9_N";
71"SMB_BMC_ALERT10_N";
72"SMB_BMC_ALERT4_N";
73"SMB_BMC_ALERT3_N";
%"LCMXO3LF2100C5BG256C"
"2","(-4750,3875)","0","pure_quanta","I1";
;
PART_NUMBER"AJ021000T03"
VALUE"LCMXO3LF-2100C-5BG256C"
MATERIAL"IC"
PART_TYPE"SMLF"
CDS_LMAN_SYM_OUTLINE"-725,1425,725,-1425"
NEEDS_NO_SIZE"TRUE"
CDS_LIB"pure_quanta"
LOCATION"U25"
$SEC"2"
CDS_SEC"2";
"VCCIO1_H10"
$PN"H10"1;
"VCCIO1_E13"
$PN"E13"1;
"VCCIO1_J10"
$PN"J10"3;
"VCCIO1_M13"
$PN"M13"3;
"PR5B"
$PN"G14"0;
"PR5A"
$PN"G15"0;
"PR9D"
$PN"J13"44;
"PR9C"
$PN"H11"43;
"PR7D"
$PN"J14"42;
"PR7C"
$PN"J16"41;
"PR6D"
$PN"J12"40;
"PR6C"
$PN"H13"39;
"PR4B"
$PN"F16"0;
"PR4A"
$PN"F14"56;
"PR5D"
$PN"H12"19;
"PR5C"
$PN"G11"20;
"PR3B"
$PN"F15"54;
"PR3A"
$PN"E16"53;
"PR4D"
$PN"G13"30;
"PR4C"
$PN"F12"32;
"PR3D"
$PN"G12"33;
"PR3C"
$PN"F13"34;
"PR2D"
$PN"D15"35;
"PR2C"
$PN"C16"36;
"PR2B"
$PN"E14"52;
"PR2A"
$PN"D16"51;
"PR1D"
$PN"B16"37;
"PR1C"
$PN"C15"38;
"PR1B"
$PN"E15"50;
"PR1A"
$PN"D14"49;
"PR9B"
$PN"K16"0;
"PR9A"
$PN"J15"6;
"PR10B"
$PN"K15"8;
"PR10A"
$PN"K14"7;
"PR11B"
$PN"L14"10;
"PR11A"
$PN"L16"9;
"PR11D"
$PN"K12"12;
"PR11C"
$PN"K13"11;
"PR12B"
$PN"M16"0;
"PR12A"
$PN"L15"0;
"PR13B"
$PN"M15"16;
"PR13A"
$PN"M14"27;
"PR14D"
$PN"R16"25;
"PR14C"
$PN"P15"0;
"PR14B"
$PN"N14"18;
"PR14A"
$PN"N16"17;
"PR13D"
$PN"P16"0;
"PR13C"
$PN"N15"45;
"PR7B||PCLKC1_0"
$PN"H16"0;
"PR7A||PCLKT1_0"
$PN"H14"0;
"PR12D"
$PN"L13"24;
"PR12C"
$PN"K11"23;
"PR6B"
$PN"H15"5;
"PR6A"
$PN"G16"55;
"PR10D"
$PN"L12"22;
"PR10C"
$PN"J11"0;
%"Q_RES"
"1","(-1800,3850)","0","pure_quanta","I100";
;
VALUE"0"
MATERIAL"CHIP"
PART_NUMBER"CS00002JB13"
PACK_TYPE"0402LF"
WATTAGE"1/16W"
TOLERANCE"5%"
CDS_LIB"pure_quanta"
SEC_TYPE"0402LF"
LOCATION"R432"
SEC"1";
"B"
$PN"2"47;
"A"
$PN"1"7;
%"UNIVERSAL_POWER"
"1","(-6000,2750)","0","logical_power","I122";
;
HDL_POWER"VCCIO1"
CDS_LIB"logical_power";
"A"1;
%"UNIVERSAL_POWER"
"1","(-3500,2750)","0","logical_power","I123";
;
HDL_POWER"VCCIO1"
CDS_LIB"logical_power";
"A"3;
%"Q_RES"
"1","(-6800,3600)","0","pure_quanta","I131";
;
MATERIAL"EMPTY"
VALUE"0"
SEC_TYPE"0402LF"
CDS_LIB"pure_quanta"
TOLERANCE"5%"
WATTAGE"1/16W"
PACK_TYPE"0402LF"
PART_NUMBER"CS00002JB13"
$LOCATION"R463"
CDS_LOCATION"R463"
SEC"1";
"B"
$PN"2"45;
"A"
$PN"1"58;
%"VCCAUX15"
"1","(-8525,2425)","0","logical_power","I133";
;
HDL_POWER"P3V3_AUX"
CDS_LIB"logical_power";
"A"2;
%"Q_RES"
"1","(-7950,2075)","0","pure_quanta","I136";
;
VALUE"4.7K"
MATERIAL"EMPTY"
CDS_LIB"pure_quanta"
PART_NUMBER"CS24702FB06"
PACK_TYPE"0402LF"
WATTAGE"1/16W"
TOLERANCE"1%"
$LOCATION"R472"
CDS_LOCATION"R472"
$SEC"1"
CDS_SEC"1";
"B"
$PN"2"46;
"A"
$PN"1"2;
%"Q_RES"
"1","(-7300,4500)","0","pure_quanta","I137";
;
VALUE"33.2"
MATERIAL"CHIP"
CDS_LIB"pure_quanta"
PACK_TYPE"0402LF"
WATTAGE"1/16W"
PART_NUMBER"CS03322FB03"
TOLERANCE"1%"
LOCATION"R773"
$SEC"1"
CDS_SEC"1";
"B"
$PN"2"20;
"A"
$PN"1"21;
%"Q_RES"
"1","(-7300,4450)","0","pure_quanta","I138";
;
MATERIAL"CHIP"
VALUE"33.2"
CDS_LIB"pure_quanta"
PACK_TYPE"0402LF"
WATTAGE"1/16W"
PART_NUMBER"CS03322FB03"
TOLERANCE"1%"
LOCATION"R825"
$SEC"1"
CDS_SEC"1";
"B"
$PN"2"19;
"A"
$PN"1"59;
%"Q_RES"
"1","(-7300,4350)","0","pure_quanta","I139";
;
VALUE"33.2"
MATERIAL"CHIP"
CDS_LIB"pure_quanta"
PACK_TYPE"0402LF"
WATTAGE"1/16W"
PART_NUMBER"CS03322FB03"
TOLERANCE"1%"
LOCATION"R833"
$SEC"1"
CDS_SEC"1";
"B"
$PN"2"39;
"A"
$PN"1"62;
%"Q_RES"
"1","(-7300,4300)","0","pure_quanta","I140";
;
MATERIAL"CHIP"
VALUE"33.2"
CDS_LIB"pure_quanta"
PACK_TYPE"0402LF"
WATTAGE"1/16W"
PART_NUMBER"CS03322FB03"
TOLERANCE"1%"
LOCATION"R769"
$SEC"1"
CDS_SEC"1";
"B"
$PN"2"40;
"A"
$PN"1"61;
%"Q_RES"
"1","(-7300,4050)","0","pure_quanta","I141";
;
VALUE"33.2"
MATERIAL"CHIP"
CDS_LIB"pure_quanta"
PACK_TYPE"0402LF"
WATTAGE"1/16W"
PART_NUMBER"CS03322FB03"
TOLERANCE"1%"
LOCATION"R263"
$SEC"1"
CDS_SEC"1";
"B"
$PN"2"43;
"A"
$PN"1"63;
%"Q_RES"
"1","(-1800,3800)","0","pure_quanta","I142";
;
VALUE"33.2"
MATERIAL"CHIP"
CDS_LIB"pure_quanta"
PACK_TYPE"0402LF"
WATTAGE"1/16W"
PART_NUMBER"CS03322FB03"
TOLERANCE"1%"
LOCATION"R841"
$SEC"1"
CDS_SEC"1";
"B"
$PN"2"14;
"A"
$PN"1"8;
%"Q_RES"
"1","(-1800,4000)","0","pure_quanta","I143";
;
MATERIAL"CHIP"
VALUE"33.2"
CDS_LIB"pure_quanta"
PACK_TYPE"0402LF"
WATTAGE"1/16W"
PART_NUMBER"CS03322FB03"
TOLERANCE"1%"
LOCATION"R638"
$SEC"1"
CDS_SEC"1";
"B"
$PN"2"60;
"A"
$PN"1"6;
%"Q_RES"
"1","(-2250,4350)","0","pure_quanta","I144";
;
VALUE"33.2"
MATERIAL"CHIP"
CDS_LIB"pure_quanta"
PACK_TYPE"0402LF"
WATTAGE"1/16W"
PART_NUMBER"CS03322FB03"
TOLERANCE"1%"
LOCATION"R536"
$SEC"1"
CDS_SEC"1";
"B"
$PN"2"69;
"A"
$PN"1"55;
%"Q_RES"
"1","(-2250,4300)","0","pure_quanta","I145";
;
VALUE"33.2"
MATERIAL"CHIP"
CDS_LIB"pure_quanta"
PACK_TYPE"0402LF"
WATTAGE"1/16W"
PART_NUMBER"CS03322FB03"
TOLERANCE"1%"
LOCATION"R537"
$SEC"1"
CDS_SEC"1";
"B"
$PN"2"68;
"A"
$PN"1"5;
%"Q_RES"
"1","(-2250,4650)","0","pure_quanta","I146";
;
VALUE"33.2"
MATERIAL"EMPTY"
TOLERANCE"1%"
PART_NUMBER"CS03322FB03"
WATTAGE"1/16W"
PACK_TYPE"0402LF"
CDS_LIB"pure_quanta"
LOCATION"R531"
$SEC"1"
CDS_SEC"1";
"B"
$PN"2"57;
"A"
$PN"1"56;
%"Q_RES"
"1","(-2250,4750)","0","pure_quanta","I147";
;
MATERIAL"EMPTY"
VALUE"33.2"
TOLERANCE"1%"
PART_NUMBER"CS03322FB03"
WATTAGE"1/16W"
PACK_TYPE"0402LF"
CDS_LIB"pure_quanta"
LOCATION"R526"
$SEC"1"
CDS_SEC"1";
"B"
$PN"2"67;
"A"
$PN"1"54;
%"Q_RES"
"1","(-2250,4800)","0","pure_quanta","I148";
;
MATERIAL"CHIP"
VALUE"33.2"
CDS_LIB"pure_quanta"
PACK_TYPE"0402LF"
WATTAGE"1/16W"
PART_NUMBER"CS03322FB03"
TOLERANCE"1%"
LOCATION"R691"
$SEC"1"
CDS_SEC"1";
"B"
$PN"2"66;
"A"
$PN"1"53;
%"Q_RES"
"1","(-2250,4900)","0","pure_quanta","I149";
;
MATERIAL"CHIP"
VALUE"33.2"
CDS_LIB"pure_quanta"
PACK_TYPE"0402LF"
WATTAGE"1/16W"
PART_NUMBER"CS03322FB03"
TOLERANCE"1%"
LOCATION"R690"
$SEC"1"
CDS_SEC"1";
"B"
$PN"2"65;
"A"
$PN"1"52;
%"Q_DIODE"
"1","(-1825,3200)","2","pure_quanta","I150";
;
PART_NUMBER"BC000340033"
MATERIAL"EMPTY"
VALUE"SDMK0340L-7-F"
PACK_TYPE"SMLF"
NEEDS_NO_SIZE"TRUE"
PIN_NAMES_ROTATE"True"
CDS_LIB"pure_quanta"
$LOCATION"D23"
CDS_LOCATION"D23"
$SEC"1"
CDS_SEC"1";
"1"
$PN"1"15;
"2"
$PN"2"16;
%"Q_RES"
"1","(-2950,1775)","0","pure_quanta","I151";
;
VALUE"4.7K"
MATERIAL"CHIP"
CDS_LIB"pure_quanta"
PART_NUMBER"CS24702FB06"
PACK_TYPE"0402LF"
WATTAGE"1/16W"
TOLERANCE"1%"
$LOCATION"R886"
CDS_LOCATION"R886"
$SEC"1"
CDS_SEC"1";
"B"
$PN"2"26;
"A"
$PN"1"4;
%"VCCAUX15"
"1","(-3175,1900)","0","logical_power","I152";
;
HDL_POWER"P3V3_AUX"
CDS_LIB"logical_power";
"A"4;
%"Q_RES"
"1","(-7300,4950)","0","pure_quanta","I2";
;
MATERIAL"CHIP"
VALUE"0"
PART_NUMBER"CS00002JB13"
CDS_LIB"pure_quanta"
TOLERANCE"5%"
WATTAGE"1/16W"
PACK_TYPE"0402LF"
LOCATION"R453"
$SEC"1"
CDS_SEC"1";
"B"
$PN"2"36;
"A"
$PN"1"73;
%"Q_RES"
"1","(-7300,4900)","0","pure_quanta","I3";
;
MATERIAL"CHIP"
VALUE"0"
PART_NUMBER"CS00002JB13"
CDS_LIB"pure_quanta"
TOLERANCE"5%"
WATTAGE"1/16W"
PACK_TYPE"0402LF"
LOCATION"R454"
$SEC"1"
CDS_SEC"1";
"B"
$PN"2"35;
"A"
$PN"1"72;
%"Q_RES"
"1","(-7300,4800)","0","pure_quanta","I4";
;
MATERIAL"CHIP"
VALUE"0"
PACK_TYPE"0402LF"
WATTAGE"1/16W"
TOLERANCE"5%"
CDS_LIB"pure_quanta"
PART_NUMBER"CS00002JB13"
LOCATION"R456"
$SEC"1"
CDS_SEC"1";
"B"
$PN"2"34;
"A"
$PN"1"70;
%"Q_RES"
"1","(-7300,4750)","0","pure_quanta","I5";
;
MATERIAL"CHIP"
VALUE"0"
PACK_TYPE"0402LF"
WATTAGE"1/16W"
TOLERANCE"5%"
CDS_LIB"pure_quanta"
PART_NUMBER"CS00002JB13"
LOCATION"R457"
$SEC"1"
CDS_SEC"1";
"B"
$PN"2"33;
"A"
$PN"1"71;
%"Q_RES"
"1","(-7300,3400)","0","pure_quanta","I76";
;
MATERIAL"CHIP"
VALUE"0"
PART_NUMBER"CS00002JB13"
PACK_TYPE"0402LF"
WATTAGE"1/16W"
TOLERANCE"5%"
SEC_TYPE"0402LF"
CDS_LIB"pure_quanta"
LOCATION"R574"
SEC"1";
"B"
$PN"2"25;
"A"
$PN"1"48;
%"Q_RES"
"1","(-7300,4150)","0","pure_quanta","I80";
;
VALUE"0"
MATERIAL"CHIP"
PART_NUMBER"CS00002JB13"
PACK_TYPE"0402LF"
WATTAGE"1/16W"
TOLERANCE"5%"
CDS_LIB"pure_quanta"
SEC_TYPE"0402LF"
LOCATION"R51"
SEC"1";
"B"
$PN"2"42;
"A"
$PN"1"64;
%"Q_RES"
"1","(-7300,4600)","0","pure_quanta","I88";
;
MATERIAL"CHIP"
VALUE"0"
SEC_TYPE"0402LF"
CDS_LIB"pure_quanta"
TOLERANCE"5%"
WATTAGE"1/16W"
PACK_TYPE"0402LF"
PART_NUMBER"CS00002JB13"
LOCATION"R271"
SEC"1";
"B"
$PN"2"30;
"A"
$PN"1"31;
%"Q_RES"
"1","(-1800,3050)","0","pure_quanta","I95";
;
VALUE"0"
MATERIAL"CHIP"
SEC_TYPE"0402LF"
CDS_LIB"pure_quanta"
TOLERANCE"5%"
WATTAGE"1/16W"
PACK_TYPE"0402LF"
PART_NUMBER"CS00002JB13"
LOCATION"R320"
SEC"1";
"B"
$PN"2"28;
"A"
$PN"1"18;
%"Q_RES"
"1","(-1800,3100)","0","pure_quanta","I98";
;
MATERIAL"CHIP"
VALUE"0"
SEC_TYPE"0402LF"
CDS_LIB"pure_quanta"
TOLERANCE"5%"
WATTAGE"1/16W"
PACK_TYPE"0402LF"
PART_NUMBER"CS00002JB13"
LOCATION"R318"
SEC"1";
"B"
$PN"2"29;
"A"
$PN"1"17;
%"Q_RES"
"1","(-2750,3250)","0","pure_quanta","I99";
;
MATERIAL"CHIP"
VALUE"0"
PART_NUMBER"CS00002JB13"
PACK_TYPE"0402LF"
WATTAGE"1/16W"
TOLERANCE"5%"
CDS_LIB"pure_quanta"
SEC_TYPE"0402LF"
LOCATION"R317"
SEC"1";
"B"
$PN"2"13;
"A"
$PN"1"27;
END.
